# T6G (Grand Teton) — schematic netlist excerpt (pin names and nets, part order shuffled) for the footprints in the layout excerpt that follows; sources: Cadence DE-HDL packaged netlist, KiCad conversion of 04192023_DAF0TMB3IC0_F0TG_MB_C_brd_V02_OCP.brd

C4179  Q_CAP  22UF 4V 20% X6S  pkg C0402  page 69 : A = PVDDCR_CPU0_P0 ; B = GND
PC8009  Q_CAP  22UF 16V 20% X6S  pkg C0805  page 198 : A = SW_P12V_AUX_PVDDCR_SOC_P0_FLT ; B = GND
C579  Q_CAP  10UF 6.3V 20% X6S  pkg C0402  page 279 : A = P0V9_CPU0_RT0_2A ; B = GND

(kicad_pcb
	(version 20260206)
	(generator "pcbnew")
	(generator_version "10.0")
	(general
		(thickness 1.6)
		(legacy_teardrops no)
	)
	(paper "A4")
	(title_block
		(title "04192023_DAF0TMB3IC0_F0TG_MB_C_brd_V02_OCP.brd")
		(comment 1 "Grand Teton / footprints 7185-7187 of 8354")
	)
	(layers
		(0 "F.Cu" signal "TOP")
		(4 "In1.Cu" signal "GND")
		(6 "In2.Cu" signal "IN1")
		(8 "In3.Cu" signal "GND1")
		(10 "In4.Cu" signal "IN2")
		(12 "In5.Cu" signal "GND2")
		(14 "In6.Cu" signal "IN3")
		(16 "In7.Cu" signal "GND3")
		(18 "In8.Cu" signal "VCC")
		(20 "In9.Cu" signal "VCC1")
		(22 "In10.Cu" signal "GND4")
		(24 "In11.Cu" signal "IN4")
		(26 "In12.Cu" signal "GND5")
		(28 "In13.Cu" signal "IN5")
		(30 "In14.Cu" signal "GND6")
		(32 "In15.Cu" signal "IN6")
		(34 "In16.Cu" signal "GND7")
		(2 "B.Cu" signal "BOTTOM")
		(9 "F.Adhes" user "F.Adhesive")
		(11 "B.Adhes" user "B.Adhesive")
		(13 "F.Paste" user "Package Geometry/Pastemask Top")
		(15 "B.Paste" user "Package Geometry/Pastemask Bottom")
		(5 "F.SilkS" user "Ref Des/Silkscreen Top")
		(7 "B.SilkS" user "Ref Des/Silkscreen Bottom")
		(1 "F.Mask" user "Board Geometry/Soldermask Top")
		(3 "B.Mask" user "Board Geometry/Soldermask Bottom")
		(17 "Dwgs.User" user "User.Drawings")
		(19 "Cmts.User" user "User.Comments")
		(21 "Eco1.User" user "User.Eco1")
		(23 "Eco2.User" user "User.Eco2")
		(25 "Edge.Cuts" user "Board Geometry/Outline")
		(27 "Margin" user)
		(31 "F.CrtYd" user "Package Geometry/Place Bound Top")
		(29 "B.CrtYd" user "Package Geometry/Place Bound Bottom")
		(35 "F.Fab" user "Ref Des/Assembly Top")
		(33 "B.Fab" user "Ref Des/Assembly Bottom")
	)
	(footprint ""
		(layer "B.Cu")
		(at 363.931454 -250.89231)
		(property "Reference" "C4179"
			(at 0 0 0)
			(layer "B.SilkS")
			(hide yes)
			(effects
				(font
					(size 1.27 1.27)
				)
				(justify mirror)
			)
		)
		(property "Value" ""
			(at 0 0 0)
			(layer "B.Fab")
			(effects
				(font
					(size 1.27 1.27)
				)
				(justify mirror)
			)
		)
		(duplicate_pad_numbers_are_jumpers no)
		(fp_line
			(start -0.7874 -0.4064)
			(end -0.7874 0.4064)
			(stroke
				(width 0.1524)
				(type default)
			)
			(layer "B.SilkS")
		)
		(fp_line
			(start -0.7874 0.4064)
			(end 0.7874 0.4064)
			(stroke
				(width 0.1524)
				(type default)
			)
			(layer "B.SilkS")
		)
		(fp_line
			(start 0.7874 -0.4064)
			(end -0.7874 -0.4064)
			(stroke
				(width 0.1524)
				(type default)
			)
			(layer "B.SilkS")
		)
		(fp_line
			(start 0.7874 0.4064)
			(end 0.7874 -0.4064)
			(stroke
				(width 0.1524)
				(type default)
			)
			(layer "B.SilkS")
		)
		(fp_line
			(start -0.67945 -0.3048)
			(end -0.67945 0.3048)
			(stroke
				(width 0.1)
				(type default)
			)
			(layer "B.Fab")
		)
		(fp_line
			(start -0.67945 0.3048)
			(end -0.120396 0.3048)
			(stroke
				(width 0.1)
				(type default)
			)
			(layer "B.Fab")
		)
		(fp_line
			(start -0.12065 -0.3048)
			(end -0.67945 -0.3048)
			(stroke
				(width 0.1)
				(type default)
			)
			(layer "B.Fab")
		)
		(fp_line
			(start -0.12065 -0.2794)
			(end -0.12065 -0.3048)
			(stroke
				(width 0.1)
				(type default)
			)
			(layer "B.Fab")
		)
		(fp_line
			(start -0.120396 0.2794)
			(end 0.12065 0.2794)
			(stroke
				(width 0.1)
				(type default)
			)
			(layer "B.Fab")
		)
		(fp_line
			(start -0.120396 0.3048)
			(end -0.120396 0.2794)
			(stroke
				(width 0.1)
				(type default)
			)
			(layer "B.Fab")
		)
		(fp_line
			(start 0.12065 -0.305054)
			(end 0.12065 -0.2794)
			(stroke
				(width 0.1)
				(type default)
			)
			(layer "B.Fab")
		)
		(fp_line
			(start 0.12065 -0.2794)
			(end -0.12065 -0.2794)
			(stroke
				(width 0.1)
				(type default)
			)
			(layer "B.Fab")
		)
		(fp_line
			(start 0.12065 0.2794)
			(end 0.12065 0.3048)
			(stroke
				(width 0.1)
				(type default)
			)
			(layer "B.Fab")
		)
		(fp_line
			(start 0.12065 0.3048)
			(end 0.67945 0.3048)
			(stroke
				(width 0.1)
				(type default)
			)
			(layer "B.Fab")
		)
		(fp_line
			(start 0.67945 -0.305054)
			(end 0.12065 -0.305054)
			(stroke
				(width 0.1)
				(type default)
			)
			(layer "B.Fab")
		)
		(fp_line
			(start 0.67945 0.3048)
			(end 0.67945 -0.305054)
			(stroke
				(width 0.1)
				(type default)
			)
			(layer "B.Fab")
		)
		(pad "1" smd circle
			(at 0.40005 0 180)
			(size 0 0)
			(layers "B.Cu" "B.Mask" "B.Paste")
			(net "PVDDCR_CPU0_P0")
		)
		(pad "2" smd circle
			(at -0.40005 0 180)
			(size 0 0)
			(layers "B.Cu" "B.Mask" "B.Paste")
			(net "GND")
		)
	)
	(footprint ""
		(layer "B.Cu")
		(at 398.880076 -169.49547 -90)
		(property "Reference" "PC8009"
			(at 0 0 90)
			(layer "B.SilkS")
			(hide yes)
			(effects
				(font
					(size 1.27 1.27)
				)
				(justify mirror)
			)
		)
		(property "Value" ""
			(at 0 0 90)
			(layer "B.Fab")
			(effects
				(font
					(size 1.27 1.27)
				)
				(justify mirror)
			)
		)
		(duplicate_pad_numbers_are_jumpers no)
		(fp_line
			(start -1.524 0.762)
			(end 1.524 0.762)
			(stroke
				(width 0.1524)
				(type default)
			)
			(layer "B.SilkS")
		)
		(fp_line
			(start 1.524 0.762)
			(end 1.524 -0.762)
			(stroke
				(width 0.1524)
				(type default)
			)
			(layer "B.SilkS")
		)
		(fp_line
			(start -1.524 -0.762)
			(end -1.524 0.762)
			(stroke
				(width 0.1524)
				(type default)
			)
			(layer "B.SilkS")
		)
		(fp_line
			(start 1.524 -0.762)
			(end -1.524 -0.762)
			(stroke
				(width 0.1524)
				(type default)
			)
			(layer "B.SilkS")
		)
		(fp_line
			(start -1.1049 0.724916)
			(end -1.1049 -0.724916)
			(stroke
				(width 0.1)
				(type default)
			)
			(layer "B.Fab")
		)
		(fp_line
			(start 1.1049 0.724916)
			(end -1.1049 0.724916)
			(stroke
				(width 0.1)
				(type default)
			)
			(layer "B.Fab")
		)
		(fp_line
			(start -1.1049 -0.724916)
			(end 1.1049 -0.724916)
			(stroke
				(width 0.1)
				(type default)
			)
			(layer "B.Fab")
		)
		(fp_line
			(start 1.1049 -0.724916)
			(end 1.1049 0.724916)
			(stroke
				(width 0.1)
				(type default)
			)
			(layer "B.Fab")
		)
		(pad "1" smd rect
			(at 0.889 0 270)
			(size 1.016 1.27)
			(layers "B.Cu" "B.Mask" "B.Paste")
			(net "SW_P12V_AUX_PVDDCR_SOC_P0_FLT")
		)
		(pad "2" smd rect
			(at -0.889 0 270)
			(size 1.016 1.27)
			(layers "B.Cu" "B.Mask" "B.Paste")
			(net "GND")
		)
	)
	(footprint ""
		(layer "B.Cu")
		(at 306.991004 -398.942052 90)
		(property "Reference" "C579"
			(at 0 0 90)
			(layer "B.SilkS")
			(hide yes)
			(effects
				(font
					(size 1.27 1.27)
				)
				(justify mirror)
			)
		)
		(property "Value" ""
			(at 0 0 90)
			(layer "B.Fab")
			(effects
				(font
					(size 1.27 1.27)
				)
				(justify mirror)
			)
		)
		(duplicate_pad_numbers_are_jumpers no)
		(fp_line
			(start 0.7874 -0.4064)
			(end -0.7874 -0.4064)
			(stroke
				(width 0.1524)
				(type default)
			)
			(layer "B.SilkS")
		)
		(fp_line
			(start -0.7874 -0.4064)
			(end -0.7874 0.4064)
			(stroke
				(width 0.1524)
				(type default)
			)
			(layer "B.SilkS")
		)
		(fp_line
			(start 0.7874 0.4064)
			(end 0.7874 -0.4064)
			(stroke
				(width 0.1524)
				(type default)
			)
			(layer "B.SilkS")
		)
		(fp_line
			(start -0.7874 0.4064)
			(end 0.7874 0.4064)
			(stroke
				(width 0.1524)
				(type default)
			)
			(layer "B.SilkS")
		)
		(fp_line
			(start 0.67945 -0.305054)
			(end 0.12065 -0.305054)
			(stroke
				(width 0.1)
				(type default)
			)
			(layer "B.Fab")
		)
		(fp_line
			(start 0.12065 -0.305054)
			(end 0.12065 -0.2794)
			(stroke
				(width 0.1)
				(type default)
			)
			(layer "B.Fab")
		)
		(fp_line
			(start -0.12065 -0.3048)
			(end -0.67945 -0.3048)
			(stroke
				(width 0.1)
				(type default)
			)
			(layer "B.Fab")
		)
		(fp_line
			(start -0.67945 -0.3048)
			(end -0.67945 0.3048)
			(stroke
				(width 0.1)
				(type default)
			)
			(layer "B.Fab")
		)
		(fp_line
			(start 0.12065 -0.2794)
			(end -0.12065 -0.2794)
			(stroke
				(width 0.1)
				(type default)
			)
			(layer "B.Fab")
		)
		(fp_line
			(start -0.12065 -0.2794)
			(end -0.12065 -0.3048)
			(stroke
				(width 0.1)
				(type default)
			)
			(layer "B.Fab")
		)
		(fp_line
			(start 0.12065 0.2794)
			(end 0.12065 0.3048)
			(stroke
				(width 0.1)
				(type default)
			)
			(layer "B.Fab")
		)
		(fp_line
			(start -0.120396 0.2794)
			(end 0.12065 0.2794)
			(stroke
				(width 0.1)
				(type default)
			)
			(layer "B.Fab")
		)
		(fp_line
			(start 0.67945 0.3048)
			(end 0.67945 -0.305054)
			(stroke
				(width 0.1)
				(type default)
			)
			(layer "B.Fab")
		)
		(fp_line
			(start 0.12065 0.3048)
			(end 0.67945 0.3048)
			(stroke
				(width 0.1)
				(type default)
			)
			(layer "B.Fab")
		)
		(fp_line
			(start -0.120396 0.3048)
			(end -0.120396 0.2794)
			(stroke
				(width 0.1)
				(type default)
			)
			(layer "B.Fab")
		)
		(fp_line
			(start -0.67945 0.3048)
			(end -0.120396 0.3048)
			(stroke
				(width 0.1)
				(type default)
			)
			(layer "B.Fab")
		)
		(pad "1" smd circle
			(at 0.40005 0 270)
			(size 0 0)
			(layers "B.Cu" "B.Mask" "B.Paste")
			(net "P0V9_CPU0_RT0_2A")
		)
		(pad "2" smd circle
			(at -0.40005 0 270)
			(size 0 0)
			(layers "B.Cu" "B.Mask" "B.Paste")
			(net "GND")
		)
	)
)
